# S9S_MB_2U (Grand Teton) — schematic netlist excerpt (pin names and nets, part order shuffled) for the footprints in the layout excerpt that follows; sources: Cadence DE-HDL packaged netlist, KiCad conversion of 03242023_DA0F0TMBIJ0_F0T_Motherboard_J_brd_V01_OCP.brd

C1708  Q_CAP  0.1UF 25V 10% EMPTY  pkg 0402  page 234 : A = P3V3_AUX ; B = GND
C1937  Q_CAP  10UF 6.3V 20% X6S  pkg C0402  page 217 : A = P3V3_AUX_FPGA_VCCIO2 ; B = GND

(kicad_pcb
	(version 20260206)
	(generator "pcbnew")
	(generator_version "10.0")
	(general
		(thickness 1.6)
		(legacy_teardrops no)
	)
	(paper "A4")
	(title_block
		(title "03242023_DA0F0TMBIJ0_F0T_Motherboard_J_brd_V01_OCP.brd")
		(comment 1 "Grand Teton / footprints 4324-4325 of 6105")
	)
	(layers
		(0 "F.Cu" signal "TOP")
		(4 "In1.Cu" signal "GND")
		(6 "In2.Cu" signal "IN1")
		(8 "In3.Cu" signal "GND1")
		(10 "In4.Cu" signal "IN2")
		(12 "In5.Cu" signal "GND2")
		(14 "In6.Cu" signal "IN3")
		(16 "In7.Cu" signal "GND3")
		(18 "In8.Cu" signal "VCC")
		(20 "In9.Cu" signal "VCC1")
		(22 "In10.Cu" signal "GND4")
		(24 "In11.Cu" signal "IN4")
		(26 "In12.Cu" signal "GND5")
		(28 "In13.Cu" signal "IN5")
		(30 "In14.Cu" signal "GND6")
		(32 "In15.Cu" signal "IN6")
		(34 "In16.Cu" signal "GND7")
		(2 "B.Cu" signal "BOTTOM")
		(9 "F.Adhes" user "F.Adhesive")
		(11 "B.Adhes" user "B.Adhesive")
		(13 "F.Paste" user "Package Geometry/Pastemask Top")
		(15 "B.Paste" user "Package Geometry/Pastemask Bottom")
		(5 "F.SilkS" user "Ref Des/Silkscreen Top")
		(7 "B.SilkS" user "Ref Des/Silkscreen Bottom")
		(1 "F.Mask" user "Board Geometry/Soldermask Top")
		(3 "B.Mask" user "Board Geometry/Soldermask Bottom")
		(17 "Dwgs.User" user "User.Drawings")
		(19 "Cmts.User" user "User.Comments")
		(21 "Eco1.User" user "User.Eco1")
		(23 "Eco2.User" user "User.Eco2")
		(25 "Edge.Cuts" user "Board Geometry/Outline")
		(27 "Margin" user)
		(31 "F.CrtYd" user "Package Geometry/Place Bound Top")
		(29 "B.CrtYd" user "Package Geometry/Place Bound Bottom")
		(35 "F.Fab" user "Ref Des/Assembly Top")
		(33 "B.Fab" user "Ref Des/Assembly Bottom")
	)
	(footprint ""
		(layer "B.Cu")
		(at 187.88888 -103.723948 180)
		(property "Reference" "C1937"
			(at 0 0 0)
			(layer "B.SilkS")
			(hide yes)
			(effects
				(font
					(size 1.27 1.27)
				)
				(justify mirror)
			)
		)
		(property "Value" ""
			(at 0 0 0)
			(layer "B.Fab")
			(effects
				(font
					(size 1.27 1.27)
				)
				(justify mirror)
			)
		)
		(duplicate_pad_numbers_are_jumpers no)
		(fp_line
			(start 0.7874 0.4064)
			(end 0.7874 -0.4064)
			(stroke
				(width 0.1524)
				(type default)
			)
			(layer "B.SilkS")
		)
		(fp_line
			(start 0.7874 -0.4064)
			(end -0.7874 -0.4064)
			(stroke
				(width 0.1524)
				(type default)
			)
			(layer "B.SilkS")
		)
		(fp_line
			(start -0.7874 0.4064)
			(end 0.7874 0.4064)
			(stroke
				(width 0.1524)
				(type default)
			)
			(layer "B.SilkS")
		)
		(fp_line
			(start -0.7874 -0.4064)
			(end -0.7874 0.4064)
			(stroke
				(width 0.1524)
				(type default)
			)
			(layer "B.SilkS")
		)
		(fp_line
			(start 0.67945 0.3048)
			(end 0.67945 -0.305054)
			(stroke
				(width 0.1)
				(type default)
			)
			(layer "B.Fab")
		)
		(fp_line
			(start 0.67945 -0.305054)
			(end 0.12065 -0.305054)
			(stroke
				(width 0.1)
				(type default)
			)
			(layer "B.Fab")
		)
		(fp_line
			(start 0.12065 0.3048)
			(end 0.67945 0.3048)
			(stroke
				(width 0.1)
				(type default)
			)
			(layer "B.Fab")
		)
		(fp_line
			(start 0.12065 0.2794)
			(end 0.12065 0.3048)
			(stroke
				(width 0.1)
				(type default)
			)
			(layer "B.Fab")
		)
		(fp_line
			(start 0.12065 -0.2794)
			(end -0.12065 -0.2794)
			(stroke
				(width 0.1)
				(type default)
			)
			(layer "B.Fab")
		)
		(fp_line
			(start 0.12065 -0.305054)
			(end 0.12065 -0.2794)
			(stroke
				(width 0.1)
				(type default)
			)
			(layer "B.Fab")
		)
		(fp_line
			(start -0.120396 0.3048)
			(end -0.120396 0.2794)
			(stroke
				(width 0.1)
				(type default)
			)
			(layer "B.Fab")
		)
		(fp_line
			(start -0.120396 0.2794)
			(end 0.12065 0.2794)
			(stroke
				(width 0.1)
				(type default)
			)
			(layer "B.Fab")
		)
		(fp_line
			(start -0.12065 -0.2794)
			(end -0.12065 -0.3048)
			(stroke
				(width 0.1)
				(type default)
			)
			(layer "B.Fab")
		)
		(fp_line
			(start -0.12065 -0.3048)
			(end -0.67945 -0.3048)
			(stroke
				(width 0.1)
				(type default)
			)
			(layer "B.Fab")
		)
		(fp_line
			(start -0.67945 0.3048)
			(end -0.120396 0.3048)
			(stroke
				(width 0.1)
				(type default)
			)
			(layer "B.Fab")
		)
		(fp_line
			(start -0.67945 -0.3048)
			(end -0.67945 0.3048)
			(stroke
				(width 0.1)
				(type default)
			)
			(layer "B.Fab")
		)
		(pad "1" smd circle
			(at 0.40005 0)
			(size 0 0)
			(layers "B.Cu" "B.Mask" "B.Paste")
			(net "P3V3_AUX_FPGA_VCCIO2")
		)
		(pad "2" smd circle
			(at -0.40005 0)
			(size 0 0)
			(layers "B.Cu" "B.Mask" "B.Paste")
			(net "GND")
		)
	)
	(footprint ""
		(layer "B.Cu")
		(at 365.82604 -398.976088)
		(property "Reference" "C1708"
			(at 0 0 0)
			(layer "B.SilkS")
			(hide yes)
			(effects
				(font
					(size 1.27 1.27)
				)
				(justify mirror)
			)
		)
		(property "Value" ""
			(at 0 0 0)
			(layer "B.Fab")
			(effects
				(font
					(size 1.27 1.27)
				)
				(justify mirror)
			)
		)
		(duplicate_pad_numbers_are_jumpers no)
		(fp_line
			(start -0.7874 -0.4064)
			(end -0.7874 0.4064)
			(stroke
				(width 0.1524)
				(type default)
			)
			(layer "B.SilkS")
		)
		(fp_line
			(start -0.7874 0.4064)
			(end 0.7874 0.4064)
			(stroke
				(width 0.1524)
				(type default)
			)
			(layer "B.SilkS")
		)
		(fp_line
			(start 0.7874 -0.4064)
			(end -0.7874 -0.4064)
			(stroke
				(width 0.1524)
				(type default)
			)
			(layer "B.SilkS")
		)
		(fp_line
			(start 0.7874 0.4064)
			(end 0.7874 -0.4064)
			(stroke
				(width 0.1524)
				(type default)
			)
			(layer "B.SilkS")
		)
		(fp_line
			(start -0.67945 -0.3048)
			(end -0.67945 0.3048)
			(stroke
				(width 0.1)
				(type default)
			)
			(layer "B.Fab")
		)
		(fp_line
			(start -0.67945 0.3048)
			(end -0.120396 0.3048)
			(stroke
				(width 0.1)
				(type default)
			)
			(layer "B.Fab")
		)
		(fp_line
			(start -0.12065 -0.3048)
			(end -0.67945 -0.3048)
			(stroke
				(width 0.1)
				(type default)
			)
			(layer "B.Fab")
		)
		(fp_line
			(start -0.12065 -0.2794)
			(end -0.12065 -0.3048)
			(stroke
				(width 0.1)
				(type default)
			)
			(layer "B.Fab")
		)
		(fp_line
			(start -0.120396 0.2794)
			(end 0.12065 0.2794)
			(stroke
				(width 0.1)
				(type default)
			)
			(layer "B.Fab")
		)
		(fp_line
			(start -0.120396 0.3048)
			(end -0.120396 0.2794)
			(stroke
				(width 0.1)
				(type default)
			)
			(layer "B.Fab")
		)
		(fp_line
			(start 0.12065 -0.305054)
			(end 0.12065 -0.2794)
			(stroke
				(width 0.1)
				(type default)
			)
			(layer "B.Fab")
		)
		(fp_line
			(start 0.12065 -0.2794)
			(end -0.12065 -0.2794)
			(stroke
				(width 0.1)
				(type default)
			)
			(layer "B.Fab")
		)
		(fp_line
			(start 0.12065 0.2794)
			(end 0.12065 0.3048)
			(stroke
				(width 0.1)
				(type default)
			)
			(layer "B.Fab")
		)
		(fp_line
			(start 0.12065 0.3048)
			(end 0.67945 0.3048)
			(stroke
				(width 0.1)
				(type default)
			)
			(layer "B.Fab")
		)
		(fp_line
			(start 0.67945 -0.305054)
			(end 0.12065 -0.305054)
			(stroke
				(width 0.1)
				(type default)
			)
			(layer "B.Fab")
		)
		(fp_line
			(start 0.67945 0.3048)
			(end 0.67945 -0.305054)
			(stroke
				(width 0.1)
				(type default)
			)
			(layer "B.Fab")
		)
		(pad "1" smd circle
			(at 0.40005 0 180)
			(size 0 0)
			(layers "B.Cu" "B.Mask" "B.Paste")
			(net "P3V3_AUX")
		)
		(pad "2" smd circle
			(at -0.40005 0 180)
			(size 0 0)
			(layers "B.Cu" "B.Mask" "B.Paste")
			(net "GND")
		)
	)
)
